#ISCELL
  logical_power cad_note *
  *
#ISCELL
  pure_quanta quanta_title_block_c *
  *
#ISCELL
  standard offpage *
  page97_i1
#ISCELL
  standard tap *
  page97_i100
#ISCELL
  standard tap *
  page97_i101
#ISCELL
  standard tap *
  page97_i102
#ISCELL
  standard tap *
  page97_i103
#ISCELL
  standard offpage *
  page97_i104
#ISCELL
  standard tap *
  page97_i105
#ISCELL
  standard tap *
  page97_i106
#ISCELL
  standard tap *
  page97_i107
#ISCELL
  standard tap *
  page97_i108
#ISCELL
  standard tap *
  page97_i109
#ISCELL
  standard offpage *
  page97_i11
#ISCELL
  standard tap *
  page97_i110
#ISCELL
  standard tap *
  page97_i111
#ISCELL
  standard tap *
  page97_i112
#ISCELL
  standard tap *
  page97_i113
#ISCELL
  standard tap *
  page97_i114
#ISCELL
  standard tap *
  page97_i115
#ISCELL
  standard tap *
  page97_i116
#ISCELL
  standard tap *
  page97_i117
#ISCELL
  standard tap *
  page97_i118
#ISCELL
  standard tap *
  page97_i119
#ISCELL
  standard offpage *
  page97_i12
#ISCELL
  standard tap *
  page97_i120
#ISCELL
  standard tap *
  page97_i121
#ISCELL
  standard tap *
  page97_i122
#ISCELL
  standard tap *
  page97_i123
#ISCELL
  standard tap *
  page97_i124
#ISCELL
  standard tap *
  page97_i125
#ISCELL
  standard tap *
  page97_i126
#ISCELL
  standard tap *
  page97_i127
#ISCELL
  standard tap *
  page97_i128
#ISCELL
  standard tap *
  page97_i129
#ISCELL
  standard offpage *
  page97_i13
#ISCELL
  standard tap *
  page97_i130
#ISCELL
  standard offpage *
  page97_i131
#ISCELL
  standard tap *
  page97_i133
#ISCELL
  standard tap *
  page97_i134
#ISCELL
  standard tap *
  page97_i135
#ISCELL
  standard tap *
  page97_i136
#ISCELL
  standard tap *
  page97_i137
#ISCELL
  standard tap *
  page97_i138
#ISCELL
  standard tap *
  page97_i139
#ISCELL
  standard offpage *
  page97_i14
#ISCELL
  standard tap *
  page97_i140
#ISCELL
  standard tap *
  page97_i141
#ISCELL
  standard tap *
  page97_i142
#ISCELL
  standard tap *
  page97_i143
#ISCELL
  standard tap *
  page97_i144
#ISCELL
  standard tap *
  page97_i145
#ISCELL
  standard tap *
  page97_i146
#ISCELL
  standard tap *
  page97_i147
#ISCELL
  standard tap *
  page97_i148
#ISCELL
  standard tap *
  page97_i149
#ISCELL
  standard offpage *
  page97_i15
#ISCELL
  standard tap *
  page97_i150
#ISCELL
  standard tap *
  page97_i151
#ISCELL
  standard tap *
  page97_i152
#ISCELL
  standard tap *
  page97_i153
#ISCELL
  standard tap *
  page97_i154
#ISCELL
  standard tap *
  page97_i155
#ISCELL
  standard tap *
  page97_i156
#ISCELL
  standard tap *
  page97_i157
#ISCELL
  standard tap *
  page97_i158
#ISCELL
  standard tap *
  page97_i159
#ISCELL
  standard offpage *
  page97_i16
#ISCELL
  standard tap *
  page97_i160
#ISCELL
  standard tap *
  page97_i161
#ISCELL
  standard tap *
  page97_i162
#ISCELL
  standard tap *
  page97_i163
#ISCELL
  standard tap *
  page97_i164
#ISCELL
  standard tap *
  page97_i165
#ISCELL
  standard tap *
  page97_i166
#ISCELL
  standard tap *
  page97_i167
#ISCELL
  standard tap *
  page97_i168
#ISCELL
  standard tap *
  page97_i169
#ISCELL
  standard offpage *
  page97_i17
#ISCELL
  standard tap *
  page97_i170
#ISCELL
  standard tap *
  page97_i171
#ISCELL
  standard tap *
  page97_i172
#ISCELL
  standard offpage *
  page97_i173
#ISCELL
  standard offpage *
  page97_i174
#ISCELL
  standard offpage *
  page97_i175
#ISCELL
  standard offpage *
  page97_i176
#ISCELL
  logical_power vcc_core *
  page97_i177
#CELL
  pure_quanta sconn288_adr50017p087cc *
  page97_i178
#CELL
  pure_quanta q_res *
  page97_i179
#ISCELL
  standard offpage *
  page97_i18
#ISCELL
  standard offpage *
  page97_i180
#ISCELL
  standard offpage *
  page97_i19
#ISCELL
  standard offpage *
  page97_i2
#ISCELL
  standard offpage *
  page97_i20
#ISCELL
  standard offpage *
  page97_i21
#ISCELL
  standard offpage *
  page97_i22
#ISCELL
  standard offpage *
  page97_i23
#ISCELL
  standard offpage *
  page97_i24
#ISCELL
  logical_power vcc_core *
  page97_i25
#ISCELL
  standard tap *
  page97_i26
#ISCELL
  standard tap *
  page97_i27
#ISCELL
  standard tap *
  page97_i28
#ISCELL
  standard tap *
  page97_i29
#ISCELL
  standard offpage *
  page97_i3
#ISCELL
  standard tap *
  page97_i30
#ISCELL
  standard tap *
  page97_i31
#ISCELL
  standard tap *
  page97_i32
#ISCELL
  standard tap *
  page97_i33
#ISCELL
  standard tap *
  page97_i34
#ISCELL
  standard tap *
  page97_i35
#ISCELL
  standard tap *
  page97_i36
#ISCELL
  standard tap *
  page97_i37
#ISCELL
  standard tap *
  page97_i38
#ISCELL
  standard tap *
  page97_i39
#ISCELL
  logical_power universal_gnd *
  page97_i4
#ISCELL
  standard tap *
  page97_i40
#ISCELL
  standard tap *
  page97_i41
#ISCELL
  standard tap *
  page97_i42
#ISCELL
  standard tap *
  page97_i43
#ISCELL
  standard tap *
  page97_i44
#ISCELL
  standard tap *
  page97_i45
#ISCELL
  standard tap *
  page97_i46
#ISCELL
  standard tap *
  page97_i47
#ISCELL
  standard tap *
  page97_i48
#ISCELL
  standard tap *
  page97_i49
#CELL
  pure_quanta q_res *
  page97_i5
#ISCELL
  standard tap *
  page97_i50
#ISCELL
  standard tap *
  page97_i51
#ISCELL
  standard tap *
  page97_i52
#ISCELL
  standard tap *
  page97_i53
#ISCELL
  standard tap *
  page97_i54
#ISCELL
  standard tap *
  page97_i55
#CELL
  pure_quanta q_cap *
  page97_i56
#ISCELL
  logical_power universal_gnd *
  page97_i57
#ISCELL
  logical_power vcc_core *
  page97_i58
#CELL
  pure_quanta q_cap *
  page97_i59
#CELL
  pure_quanta sconn288_adr50017p087cc *
  page97_i6
#ISCELL
  logical_power vcc_core *
  page97_i60
#ISCELL
  logical_power universal_gnd *
  page97_i61
#CELL
  pure_quanta q_cap *
  page97_i62
#ISCELL
  logical_power universal_gnd *
  page97_i63
#CELL
  pure_quanta sconn288_adr50017p087cc *
  page97_i64
#ISCELL
  logical_power universal_gnd *
  page97_i65
#ISCELL
  standard tap *
  page97_i66
#ISCELL
  standard tap *
  page97_i67
#ISCELL
  standard tap *
  page97_i68
#ISCELL
  standard tap *
  page97_i69
#ISCELL
  standard offpage *
  page97_i7
#ISCELL
  standard tap *
  page97_i70
#ISCELL
  standard tap *
  page97_i71
#ISCELL
  standard tap *
  page97_i72
#ISCELL
  standard tap *
  page97_i73
#ISCELL
  standard tap *
  page97_i74
#ISCELL
  standard tap *
  page97_i75
#ISCELL
  standard tap *
  page97_i76
#ISCELL
  standard tap *
  page97_i77
#ISCELL
  standard tap *
  page97_i78
#ISCELL
  standard tap *
  page97_i79
#ISCELL
  standard offpage *
  page97_i8
#ISCELL
  standard tap *
  page97_i80
#ISCELL
  standard tap *
  page97_i81
#ISCELL
  standard tap *
  page97_i82
#ISCELL
  standard tap *
  page97_i83
#ISCELL
  standard tap *
  page97_i84
#ISCELL
  standard tap *
  page97_i85
#ISCELL
  standard tap *
  page97_i86
#ISCELL
  standard tap *
  page97_i87
#ISCELL
  standard tap *
  page97_i88
#ISCELL
  standard tap *
  page97_i89
#ISCELL
  standard offpage *
  page97_i9
#ISCELL
  standard tap *
  page97_i90
#ISCELL
  standard tap *
  page97_i91
#ISCELL
  standard tap *
  page97_i92
#ISCELL
  standard tap *
  page97_i93
#ISCELL
  standard tap *
  page97_i94
#ISCELL
  standard tap *
  page97_i95
#ISCELL
  standard tap *
  page97_i96
#ISCELL
  standard tap *
  page97_i97
#ISCELL
  standard tap *
  page97_i98
#ISCELL
  standard tap *
  page97_i99
